# T6G (Grand Teton) — schematic netlist excerpt (pin names and nets, part order shuffled) for the footprints in the layout excerpt that follows; sources: Cadence DE-HDL packaged netlist, KiCad conversion of 04192023_DAF0TMB3IC0_F0TG_MB_C_brd_V02_OCP.brd

R1731  Q_RES  10K 1% EMPTY  pkg 0402LF  page 171 : A = P3V3_AUX ; B = JTAG_SCM_TMS
C954  Q_CAP_DIFFBUS  DIFF BUS_0.22UF 6.3V 20% X6S  pkg C0201  page 63 : \1\ = P5E_CPU0_P1_TX_C_DN<5> ; \2\ = P5E_CPU0_P1_TX_DN<5>
R3848  Q_RES  10K 1% CHIP  pkg 0402LF  page 141 : A = P3V3_AUX ; B = HP_LVC3_OCP_V3_2_P12V_PWRGD

(kicad_pcb
	(version 20260206)
	(generator "pcbnew")
	(generator_version "10.0")
	(general
		(thickness 1.6)
		(legacy_teardrops no)
	)
	(paper "A4")
	(title_block
		(title "04192023_DAF0TMB3IC0_F0TG_MB_C_brd_V02_OCP.brd")
		(comment 1 "Grand Teton / footprints 3356-3358 of 8354")
	)
	(layers
		(0 "F.Cu" signal "TOP")
		(4 "In1.Cu" signal "GND")
		(6 "In2.Cu" signal "IN1")
		(8 "In3.Cu" signal "GND1")
		(10 "In4.Cu" signal "IN2")
		(12 "In5.Cu" signal "GND2")
		(14 "In6.Cu" signal "IN3")
		(16 "In7.Cu" signal "GND3")
		(18 "In8.Cu" signal "VCC")
		(20 "In9.Cu" signal "VCC1")
		(22 "In10.Cu" signal "GND4")
		(24 "In11.Cu" signal "IN4")
		(26 "In12.Cu" signal "GND5")
		(28 "In13.Cu" signal "IN5")
		(30 "In14.Cu" signal "GND6")
		(32 "In15.Cu" signal "IN6")
		(34 "In16.Cu" signal "GND7")
		(2 "B.Cu" signal "BOTTOM")
		(9 "F.Adhes" user "F.Adhesive")
		(11 "B.Adhes" user "B.Adhesive")
		(13 "F.Paste" user "Package Geometry/Pastemask Top")
		(15 "B.Paste" user "Package Geometry/Pastemask Bottom")
		(5 "F.SilkS" user "Ref Des/Silkscreen Top")
		(7 "B.SilkS" user "Ref Des/Silkscreen Bottom")
		(1 "F.Mask" user "Board Geometry/Soldermask Top")
		(3 "B.Mask" user "Board Geometry/Soldermask Bottom")
		(17 "Dwgs.User" user "User.Drawings")
		(19 "Cmts.User" user "User.Comments")
		(21 "Eco1.User" user "User.Eco1")
		(23 "Eco2.User" user "User.Eco2")
		(25 "Edge.Cuts" user "Board Geometry/Outline")
		(27 "Margin" user)
		(31 "F.CrtYd" user "Package Geometry/Place Bound Top")
		(29 "B.CrtYd" user "Package Geometry/Place Bound Bottom")
		(35 "F.Fab" user "Ref Des/Assembly Top")
		(33 "B.Fab" user "Ref Des/Assembly Bottom")
	)
	(footprint ""
		(layer "F.Cu")
		(at 339.238844 -381.41783 -90)
		(property "Reference" "C954"
			(at 0 0 270)
			(layer "F.SilkS")
			(hide yes)
			(effects
				(font
					(size 1.27 1.27)
				)
			)
		)
		(property "Value" ""
			(at 0 0 270)
			(layer "F.Fab")
			(effects
				(font
					(size 1.27 1.27)
				)
			)
		)
		(duplicate_pad_numbers_are_jumpers no)
		(fp_line
			(start -0.299974 0.150114)
			(end -0.299974 -0.150114)
			(stroke
				(width 0.1)
				(type default)
			)
			(layer "F.Fab")
		)
		(fp_line
			(start 0.299974 0.150114)
			(end -0.299974 0.150114)
			(stroke
				(width 0.1)
				(type default)
			)
			(layer "F.Fab")
		)
		(fp_line
			(start -0.299974 -0.150114)
			(end 0.299974 -0.150114)
			(stroke
				(width 0.1)
				(type default)
			)
			(layer "F.Fab")
		)
		(fp_line
			(start 0.299974 -0.150114)
			(end 0.299974 0.150114)
			(stroke
				(width 0.1)
				(type default)
			)
			(layer "F.Fab")
		)
		(pad "1" smd rect
			(at -0.2667 0 270)
			(size 0.3048 0.381)
			(layers "F.Cu" "F.Mask" "F.Paste")
			(net "P5E_CPU0_P1_TX_C_DN<5>")
		)
		(pad "2" smd rect
			(at 0.2667 0 270)
			(size 0.3048 0.381)
			(layers "F.Cu" "F.Mask" "F.Paste")
			(net "P5E_CPU0_P1_TX_DN<5>")
		)
	)
	(footprint ""
		(layer "F.Cu")
		(at 63.194438 -28.382722)
		(property "Reference" "R3848"
			(at 0 0 0)
			(layer "F.SilkS")
			(hide yes)
			(effects
				(font
					(size 1.27 1.27)
				)
			)
		)
		(property "Value" ""
			(at 0 0 0)
			(layer "F.Fab")
			(effects
				(font
					(size 1.27 1.27)
				)
			)
		)
		(duplicate_pad_numbers_are_jumpers no)
		(fp_line
			(start -0.7874 -0.4064)
			(end 0.7874 -0.4064)
			(stroke
				(width 0.1524)
				(type default)
			)
			(layer "F.SilkS")
		)
		(fp_line
			(start -0.7874 0.4064)
			(end -0.7874 -0.4064)
			(stroke
				(width 0.1524)
				(type default)
			)
			(layer "F.SilkS")
		)
		(fp_line
			(start 0.7874 -0.4064)
			(end 0.7874 0.4064)
			(stroke
				(width 0.1524)
				(type default)
			)
			(layer "F.SilkS")
		)
		(fp_line
			(start 0.7874 0.4064)
			(end -0.7874 0.4064)
			(stroke
				(width 0.1524)
				(type default)
			)
			(layer "F.SilkS")
		)
		(fp_line
			(start -0.67945 -0.305054)
			(end -0.12065 -0.305054)
			(stroke
				(width 0.1)
				(type default)
			)
			(layer "F.Fab")
		)
		(fp_line
			(start -0.67945 0.3048)
			(end -0.67945 -0.305054)
			(stroke
				(width 0.1)
				(type default)
			)
			(layer "F.Fab")
		)
		(fp_line
			(start -0.12065 -0.305054)
			(end -0.12065 -0.2794)
			(stroke
				(width 0.1)
				(type default)
			)
			(layer "F.Fab")
		)
		(fp_line
			(start -0.12065 -0.2794)
			(end 0.12065 -0.2794)
			(stroke
				(width 0.1)
				(type default)
			)
			(layer "F.Fab")
		)
		(fp_line
			(start -0.12065 0.2794)
			(end -0.12065 0.3048)
			(stroke
				(width 0.1)
				(type default)
			)
			(layer "F.Fab")
		)
		(fp_line
			(start -0.12065 0.3048)
			(end -0.67945 0.3048)
			(stroke
				(width 0.1)
				(type default)
			)
			(layer "F.Fab")
		)
		(fp_line
			(start 0.120396 0.2794)
			(end -0.12065 0.2794)
			(stroke
				(width 0.1)
				(type default)
			)
			(layer "F.Fab")
		)
		(fp_line
			(start 0.120396 0.3048)
			(end 0.120396 0.2794)
			(stroke
				(width 0.1)
				(type default)
			)
			(layer "F.Fab")
		)
		(fp_line
			(start 0.12065 -0.3048)
			(end 0.67945 -0.3048)
			(stroke
				(width 0.1)
				(type default)
			)
			(layer "F.Fab")
		)
		(fp_line
			(start 0.12065 -0.2794)
			(end 0.12065 -0.3048)
			(stroke
				(width 0.1)
				(type default)
			)
			(layer "F.Fab")
		)
		(fp_line
			(start 0.67945 -0.3048)
			(end 0.67945 0.3048)
			(stroke
				(width 0.1)
				(type default)
			)
			(layer "F.Fab")
		)
		(fp_line
			(start 0.67945 0.3048)
			(end 0.120396 0.3048)
			(stroke
				(width 0.1)
				(type default)
			)
			(layer "F.Fab")
		)
		(pad "1" smd circle
			(at -0.40005 0)
			(size 0 0)
			(layers "F.Cu" "F.Mask" "F.Paste")
			(net "P3V3_AUX")
		)
		(pad "2" smd circle
			(at 0.40005 0)
			(size 0 0)
			(layers "F.Cu" "F.Mask" "F.Paste")
			(net "HP_LVC3_OCP_V3_2_P12V_PWRGD")
		)
	)
	(footprint ""
		(layer "F.Cu")
		(at 105.64876 -59.802268)
		(property "Reference" "R1731"
			(at 0 0 0)
			(layer "F.SilkS")
			(hide yes)
			(effects
				(font
					(size 1.27 1.27)
				)
			)
		)
		(property "Value" ""
			(at 0 0 0)
			(layer "F.Fab")
			(effects
				(font
					(size 1.27 1.27)
				)
			)
		)
		(duplicate_pad_numbers_are_jumpers no)
		(fp_line
			(start -0.7874 -0.4064)
			(end 0.7874 -0.4064)
			(stroke
				(width 0.1524)
				(type default)
			)
			(layer "F.SilkS")
		)
		(fp_line
			(start -0.7874 0.4064)
			(end -0.7874 -0.4064)
			(stroke
				(width 0.1524)
				(type default)
			)
			(layer "F.SilkS")
		)
		(fp_line
			(start 0.7874 -0.4064)
			(end 0.7874 0.4064)
			(stroke
				(width 0.1524)
				(type default)
			)
			(layer "F.SilkS")
		)
		(fp_line
			(start 0.7874 0.4064)
			(end -0.7874 0.4064)
			(stroke
				(width 0.1524)
				(type default)
			)
			(layer "F.SilkS")
		)
		(fp_line
			(start -0.67945 -0.305054)
			(end -0.12065 -0.305054)
			(stroke
				(width 0.1)
				(type default)
			)
			(layer "F.Fab")
		)
		(fp_line
			(start -0.67945 0.3048)
			(end -0.67945 -0.305054)
			(stroke
				(width 0.1)
				(type default)
			)
			(layer "F.Fab")
		)
		(fp_line
			(start -0.12065 -0.305054)
			(end -0.12065 -0.2794)
			(stroke
				(width 0.1)
				(type default)
			)
			(layer "F.Fab")
		)
		(fp_line
			(start -0.12065 -0.2794)
			(end 0.12065 -0.2794)
			(stroke
				(width 0.1)
				(type default)
			)
			(layer "F.Fab")
		)
		(fp_line
			(start -0.12065 0.2794)
			(end -0.12065 0.3048)
			(stroke
				(width 0.1)
				(type default)
			)
			(layer "F.Fab")
		)
		(fp_line
			(start -0.12065 0.3048)
			(end -0.67945 0.3048)
			(stroke
				(width 0.1)
				(type default)
			)
			(layer "F.Fab")
		)
		(fp_line
			(start 0.120396 0.2794)
			(end -0.12065 0.2794)
			(stroke
				(width 0.1)
				(type default)
			)
			(layer "F.Fab")
		)
		(fp_line
			(start 0.120396 0.3048)
			(end 0.120396 0.2794)
			(stroke
				(width 0.1)
				(type default)
			)
			(layer "F.Fab")
		)
		(fp_line
			(start 0.12065 -0.3048)
			(end 0.67945 -0.3048)
			(stroke
				(width 0.1)
				(type default)
			)
			(layer "F.Fab")
		)
		(fp_line
			(start 0.12065 -0.2794)
			(end 0.12065 -0.3048)
			(stroke
				(width 0.1)
				(type default)
			)
			(layer "F.Fab")
		)
		(fp_line
			(start 0.67945 -0.3048)
			(end 0.67945 0.3048)
			(stroke
				(width 0.1)
				(type default)
			)
			(layer "F.Fab")
		)
		(fp_line
			(start 0.67945 0.3048)
			(end 0.120396 0.3048)
			(stroke
				(width 0.1)
				(type default)
			)
			(layer "F.Fab")
		)
		(pad "1" smd circle
			(at -0.40005 0)
			(size 0 0)
			(layers "F.Cu" "F.Mask" "F.Paste")
			(net "P3V3_AUX")
		)
		(pad "2" smd circle
			(at 0.40005 0)
			(size 0 0)
			(layers "F.Cu" "F.Mask" "F.Paste")
			(net "JTAG_SCM_TMS")
		)
	)
)
